FILE_TYPE = CONNECTIVITY;
{Allegro Design Entry HDL 17.2-2016 S081 (4005846) 1/11/2022}
"PAGE_NUMBER" = 321;
0"NC";
1"P3V3\g";
2"P3V3\g";
3"GND\g";
4"GND\g";
5"GND\g";
6"GND\g";
7"PWRGD_CPUPWRGD_LVC1"CDS_PHYS_NET_NAME"PWRGD_CPUPWRGD_LVC1";
8"H_CPU_RMCA_LVC1_R_N"CDS_PHYS_NET_NAME"H_CPU_RMCA_LVC1_R_N";
9"H_CPU_CATERR_LVC1_R_N"CDS_PHYS_NET_NAME"H_CPU_CATERR_LVC1_R_N";
10"H_CPU_CATERR_LVC2_BMC_R_N";
11"H_CPU_CATERR_LVC2_R1_N"CDS_PHYS_NET_NAME"RST_CPU0_DRAM_EF_PLD_N";
12"H_CPU_RMCA_LVC2_R1_N"CDS_PHYS_NET_NAME"RST_CPU0_DRAM_CD_PLD_N";
13"PWRGD_CPUPWRGD_LVC2_R"CDS_PHYS_NET_NAME"RST_CPU0_DRAM_AB_PLD_N";
14"PD_CPU0_ERRS_DIR";
15"H_CPU_CATERR_LVC2_BMC_N"CDS_PHYS_NET_NAME"RST_CPU0_DRAM_EF_PLD_N";
16"P0V62_CPU0_ERRS_VREF";
17"H_CPU_CATERR_LVC2_R2_N"CDS_PHYS_NET_NAME"RST_CPU0_DRAM_EF_PLD_N";
18"H_CPU_RMCA_LVC2_R2_N"CDS_PHYS_NET_NAME"RST_CPU0_DRAM_CD_PLD_N";
19"PWRGD_CPUPWRGD_LVC2_R1"CDS_PHYS_NET_NAME"RST_CPU0_DRAM_AB_PLD_N";
%"Q_RES"
"1","(1050,1200)","0","pure_quanta","I101";
;
PART_NUMBER"CS03322FB03"
MATERIAL"CHIP"
VALUE"33.2"
$LOCATION"R4621"
CDS_LIB"pure_quanta"
PACK_TYPE"0402LF"
TOLERANCE"1%"
WATTAGE"1/16W"
CDS_LOCATION"R4621"
$SEC"1"
CDS_SEC"1";
"B"
$PN"2"15;
"A"
$PN"1"10;
%"UNIVERSAL_GND"
"1","(900,1575)","2","logical_power","I70";
;
CDS_LIB"logical_power"
HDL_POWER"GND";
"A"5;
%"UNIVERSAL_GND"
"1","(1625,1475)","2","logical_power","I74";
;
HDL_POWER"GND"
CDS_LIB"logical_power";
"A"6;
%"UNIVERSAL_POWER"
"1","(900,2475)","0","logical_power","I75";
;
HDL_POWER"P3V3"
CDS_LIB"logical_power";
"A"2;
%"Q_RES"
"1","(1150,1550)","0","pure_quanta","I77";
;
PART_NUMBER"CS21002FB06"
MATERIAL"CHIP"
VALUE"1K"
$LOCATION"R4029"
TOLERANCE"1%"
WATTAGE"1/16W"
PACK_TYPE"0402LF"
CDS_LIB"pure_quanta"
CDS_LOCATION"R4029"
$SEC"1"
CDS_SEC"1";
"B"
$PN"2"6;
"A"
$PN"1"14;
%"Q_RES"
"1","(1050,1400)","0","pure_quanta","I78";
;
PART_NUMBER"CS03322FB03"
VALUE"33.2"
MATERIAL"CHIP"
$LOCATION"R4021"
CDS_LIB"pure_quanta"
WATTAGE"1/16W"
TOLERANCE"1%"
PACK_TYPE"0402LF"
CDS_LOCATION"R4021"
$SEC"1"
CDS_SEC"1";
"B"
$PN"2"19;
"A"
$PN"1"13;
%"Q_RES"
"1","(1050,1350)","0","pure_quanta","I79";
;
PART_NUMBER"CS03322FB03"
MATERIAL"CHIP"
VALUE"33.2"
$LOCATION"R4022"
CDS_LIB"pure_quanta"
PACK_TYPE"0402LF"
TOLERANCE"1%"
WATTAGE"1/16W"
CDS_LOCATION"R4022"
$SEC"1"
CDS_SEC"1";
"B"
$PN"2"18;
"A"
$PN"1"12;
%"Q_RES"
"1","(1050,1300)","0","pure_quanta","I80";
;
PART_NUMBER"CS03322FB03"
VALUE"33.2"
MATERIAL"CHIP"
$LOCATION"R4023"
WATTAGE"1/16W"
TOLERANCE"1%"
PACK_TYPE"0402LF"
CDS_LIB"pure_quanta"
CDS_LOCATION"R4023"
$SEC"1"
CDS_SEC"1";
"B"
$PN"2"17;
"A"
$PN"1"11;
%"Q_CAP"
"1","(525,1850)","2","pure_quanta","I83";
;
PART_NUMBER"CH4104K1B00"
TOLERANCE"10%"
VALUE"0.1UF"
VOLTAGE"25V"
MATERIAL"X7R"
PACK_TYPE"0402"
$LOCATION"C2249"
CDS_LIB"pure_quanta"
CDS_LOCATION"C2249"
$SEC"1"
CDS_SEC"1";
"B"
$PN"2"5;
"A"
$PN"1"16;
%"Q_CAP"
"1","(-75,1975)","0","pure_quanta","I85";
;
PART_NUMBER"CH5104KEB02"
VALUE"1UF"
VOLTAGE"25V"
TOLERANCE"10%"
PACK_TYPE"C0402"
MATERIAL"X6S"
$LOCATION"C2243"
CDS_LIB"pure_quanta"
CDS_LOCATION"C2243"
$SEC"1"
CDS_SEC"1";
"B"
$PN"2"4;
"A"
$PN"1"1;
%"UNIVERSAL_GND"
"1","(-75,1750)","0","logical_power","I86";
;
HDL_POWER"GND"
CDS_LIB"logical_power";
"A"4;
%"UNIVERSAL_POWER"
"1","(-225,2225)","0","logical_power","I87";
;
HDL_POWER"P3V3"
CDS_LIB"logical_power";
"A"1;
%"GTL2014PW"
"1","(-725,1350)","2","pure_quanta","I91";
;
PART_NUMBER"AL002014K01"
MATERIAL"IC"
VALUE"GTL2014PW"
PART_TYPE"SMLF"
$LOCATION"U301"
SEC_TYPE""
CDS_LIB"pure_quanta"
CDS_LMAN_SYM_OUTLINE"-250,350,250,-350"
NEEDS_NO_SIZE"TRUE"
CDS_LOCATION"U301"
SEC"1";
"VCC"
$PN"14"1;
"VREF"
$PN"4"16;
"DIR"
$PN"1"14;
"A0"
$PN"13"10;
"A1"
$PN"12"11;
"A2"
$PN"10"12;
"A3"
$PN"9"13;
"GND_0"
$PN"7"3;
"GND_1"
$PN"8"3;
"GND_2"
$PN"11"3;
"B3"
$PN"6"7;
"B2"
$PN"5"8;
"B1"
$PN"3"9;
"B0"
$PN"2"9;
%"UNIVERSAL_GND"
"1","(-1250,950)","0","logical_power","I92";
;
CDS_LIB"logical_power"
HDL_POWER"GND";
"A"3;
%"Q_RES"
"2","(900,2225)","0","pure_quanta","I97";
;
PART_NUMBER"CS24322FB03"
PACK_TYPE"0402LF"
WATTAGE"1/16W"
TOLERANCE"1%"
MATERIAL"CHIP"
VALUE"4.32K"
LOCATION"R4016"
CDS_LIB"pure_quanta"
$SEC"1"
CDS_SEC"1";
"A"
$PN"1"2;
"B"
$PN"2"16;
%"Q_RES"
"2","(900,1850)","0","pure_quanta","I98";
;
PART_NUMBER"CS21002FB06"
PACK_TYPE"0402LF"
VALUE"1K"
WATTAGE"1/16W"
MATERIAL"CHIP"
TOLERANCE"1%"
LOCATION"R4019"
CDS_LIB"pure_quanta"
$SEC"1"
CDS_SEC"1";
"A"
$PN"1"16;
"B"
$PN"2"5;
END.
